(kicad_pcb
	(version 20221018)
	(generator pcbnew)
	(general
    (thickness 1.62)
  )
	(paper "A4")
	(title_block
    (title "ECP5 - Datacenter Secure Control Module (DC-SCM)")
    (date "2024-07-01")
    (rev "1.2.1")
		(comment 9 "footprints 203-203 of 506")
	)
	(layers
    (0 "F.Cu" signal)
    (1 "In1.Cu" power)
    (2 "In2.Cu" signal)
    (3 "In3.Cu" power)
    (4 "In4.Cu" power)
    (5 "In5.Cu" signal)
    (6 "In6.Cu" power)
    (31 "B.Cu" signal)
    (32 "B.Adhes" user "B.Adhesive")
    (33 "F.Adhes" user "F.Adhesive")
    (34 "B.Paste" user)
    (35 "F.Paste" user)
    (36 "B.SilkS" user "B.Silkscreen")
    (37 "F.SilkS" user "F.Silkscreen")
    (38 "B.Mask" user)
    (39 "F.Mask" user)
    (40 "Dwgs.User" user "User.Drawings")
    (41 "Cmts.User" user "User.Comments")
    (42 "Eco1.User" user "User.Eco1")
    (43 "Eco2.User" user "User.Eco2")
    (44 "Edge.Cuts" user)
    (45 "Margin" user)
    (46 "B.CrtYd" user "B.Courtyard")
    (47 "F.CrtYd" user "F.Courtyard")
    (48 "B.Fab" user)
    (49 "F.Fab" user)
  )
	(footprint "antmicro-footprints:antmicro-logo_scaled_20mm"
		(layer "F.Cu")
    (at 92.8 154.6)
    (property "Author" "Antmicro")
    (property "License" "Apache-2.0")
    (property "MPN" "")
    (property "Manufacturer" "")
    (property "Public" "False")
    (property "Sheetfile" "ecp5-dc-scm.kicad_sch")
    (property "Sheetname" "")
    (property "ki_description" "Mechanical part")
    (attr allow_soldermask_bridges)
    (fp_text reference "N1" (at 0.05 -5.5) (layer "F.SilkS") hide
        (effects (font (size 0.7 0.7) (thickness 0.15)) (justify left bottom))
    )
    (fp_text value "antmicro_logo" (at -0.101 5.099) (layer "F.SilkS") hide
        (effects (font (size 0.7 0.7) (thickness 0.15)) (justify left bottom))
    )
  )
)
